(kicad_pcb
	(version 20260206)
	(generator "pcbnew")
	(generator_version "10.0")
	(general
		(thickness 1.6)
		(legacy_teardrops no)
	)
	(paper "A4")
	(title_block
		(title "v2-tray-backplane — ms_tbp_v2.brd")
		(comment 1 "Open CloudServer (Microsoft) / footprints 59-64 of 164")
	)
	(layers
		(0 "F.Cu" signal "TOP")
		(4 "In1.Cu" signal "LYR2")
		(6 "In2.Cu" signal "LYR3")
		(8 "In3.Cu" signal "LYR4")
		(10 "In4.Cu" signal "LYR5")
		(12 "In5.Cu" signal "LYR6")
		(14 "In6.Cu" signal "LYR7")
		(2 "B.Cu" signal "BOTTOM")
		(9 "F.Adhes" user "F.Adhesive")
		(11 "B.Adhes" user "B.Adhesive")
		(13 "F.Paste" user "Package Geometry/Pastemask Top")
		(15 "B.Paste" user "Package Geometry/Pastemask Bottom")
		(5 "F.SilkS" user "Ref Des/Silkscreen Top")
		(7 "B.SilkS" user "Ref Des/Silkscreen Bottom")
		(1 "F.Mask" user "Board Geometry/Soldermask Top")
		(3 "B.Mask" user "Board Geometry/Soldermask Bottom")
		(17 "Dwgs.User" user "User.Drawings")
		(19 "Cmts.User" user "User.Comments")
		(21 "Eco1.User" user "User.Eco1")
		(23 "Eco2.User" user "User.Eco2")
		(25 "Edge.Cuts" user "Board Geometry/Outline")
		(27 "Margin" user)
		(31 "F.CrtYd" user "Package Geometry/Place Bound Top")
		(29 "B.CrtYd" user "Package Geometry/Place Bound Bottom")
		(35 "F.Fab" user "Ref Des/Assembly Top")
		(33 "B.Fab" user "Ref Des/Assembly Bottom")
	)
	(footprint ""
		(layer "F.Cu")
		(at -95.25 39.010001 180)
		(property "Reference" "J20"
			(at 8.73506 -8.843599 0)
			(unlocked yes)
			(layer "F.SilkS")
			(effects
				(font
					(size 0.762 0.5334)
					(thickness 0.1016)
				)
			)
		)
		(property "Value" ""
			(at 0 0 180)
			(layer "F.Fab")
			(effects
				(font
					(size 1.27 1.27)
				)
			)
		)
		(duplicate_pad_numbers_are_jumpers no)
		(fp_line
			(start 9.1 5.750001)
			(end 9.1 4.093401)
			(stroke
				(width 0.127)
				(type default)
			)
			(layer "F.SilkS")
		)
		(fp_line
			(start 9.1 -5.750001)
			(end 9.1 1.507599)
			(stroke
				(width 0.127)
				(type default)
			)
			(layer "F.SilkS")
		)
		(fp_line
			(start 7.5211 -5.750001)
			(end 9.1 -5.750001)
			(stroke
				(width 0.127)
				(type default)
			)
			(layer "F.SilkS")
		)
		(fp_line
			(start -8.029301 -5.750001)
			(end -9.1 -5.750001)
			(stroke
				(width 0.127)
				(type default)
			)
			(layer "F.SilkS")
		)
		(fp_line
			(start -9.1 5.750001)
			(end 9.1 5.750001)
			(stroke
				(width 0.127)
				(type default)
			)
			(layer "F.SilkS")
		)
		(fp_line
			(start -9.1 4.0408)
			(end -9.1 5.750001)
			(stroke
				(width 0.127)
				(type default)
			)
			(layer "F.SilkS")
		)
		(fp_line
			(start -9.1 -5.750001)
			(end -9.1 1.446101)
			(stroke
				(width 0.127)
				(type default)
			)
			(layer "F.SilkS")
		)
		(fp_rect
			(start -9.608 6.258001)
			(end 9.607999 -6.258002)
			(stroke
				(width 0)
				(type default)
			)
			(fill no)
			(layer "F.CrtYd")
		)
		(fp_line
			(start 9.1 5.750001)
			(end 9.1 -5.750001)
			(stroke
				(width 0.1)
				(type default)
			)
			(layer "F.Fab")
		)
		(fp_line
			(start 9.1 -5.750001)
			(end -9.1 -5.750001)
			(stroke
				(width 0.1)
				(type default)
			)
			(layer "F.Fab")
		)
		(fp_line
			(start -9.1 5.750001)
			(end 9.1 5.750001)
			(stroke
				(width 0.1)
				(type default)
			)
			(layer "F.Fab")
		)
		(fp_line
			(start -9.1 -5.750001)
			(end -9.1 5.750001)
			(stroke
				(width 0.1)
				(type default)
			)
			(layer "F.Fab")
		)
		(fp_text user "19"
			(at 8.3566 -0.131399 0)
			(unlocked yes)
			(layer "F.SilkS")
			(effects
				(font
					(size 0.762 0.5334)
					(thickness 0.1016)
				)
			)
		)
		(fp_text user "20"
			(at 8.03656 -3.992199 0)
			(unlocked yes)
			(layer "F.SilkS")
			(effects
				(font
					(size 0.762 0.5334)
					(thickness 0.1016)
				)
			)
		)
		(fp_text user "*"
			(at -8.08228 -0.650829 0)
			(unlocked yes)
			(layer "F.SilkS")
			(effects
				(font
					(size 0.381 0.381)
					(thickness 0.381)
				)
			)
		)
		(pad "" np_thru_hole circle
			(at -8.400001 2.849999 270)
			(size 1.27 1.27)
			(drill 1.5494)
			(layers "*.Cu" "*.Mask")
		)
		(pad "" np_thru_hole circle
			(at 8.400001 2.849999 270)
			(size 1.27 1.27)
			(drill 1.5494)
			(layers "*.Cu" "*.Mask")
		)
		(pad "1" smd oval
			(at -7.000001 -2.33 180)
			(size 0.3556 1.8034)
			(layers "F.Cu" "F.Mask" "F.Paste")
			(net "GND")
		)
		(pad "2" smd oval
			(at -6.2 -2.33 180)
			(size 0.3556 1.8034)
			(layers "F.Cu" "F.Mask" "F.Paste")
			(net "ETH40G_B2_TX1N")
		)
		(pad "3" smd oval
			(at -5.399999 -2.33 180)
			(size 0.3556 1.8034)
			(layers "F.Cu" "F.Mask" "F.Paste")
			(net "ETH40G_B2_TX1P")
		)
		(pad "4" smd oval
			(at -4.600001 -2.33 180)
			(size 0.3556 1.8034)
			(layers "F.Cu" "F.Mask" "F.Paste")
			(net "GND")
		)
		(pad "5" smd oval
			(at -3.8 -2.33 180)
			(size 0.3556 1.8034)
			(layers "F.Cu" "F.Mask" "F.Paste")
			(net "ETH40G_B2_TX3N")
		)
		(pad "6" smd oval
			(at -2.999999 -2.33 180)
			(size 0.3556 1.8034)
			(layers "F.Cu" "F.Mask" "F.Paste")
			(net "ETH40G_B2_TX3P")
		)
		(pad "7" smd oval
			(at -2.200001 -2.33 180)
			(size 0.3556 1.8034)
			(layers "F.Cu" "F.Mask" "F.Paste")
			(net "GND")
		)
		(pad "8" smd oval
			(at -1.4 -2.33 180)
			(size 0.3556 1.8034)
			(layers "F.Cu" "F.Mask" "F.Paste")
			(net "ETH40G_B2_MODSEL_N")
		)
		(pad "9" smd oval
			(at -0.599999 -2.33 180)
			(size 0.3556 1.8034)
			(layers "F.Cu" "F.Mask" "F.Paste")
			(net "ETH40G_B2_RESET_N")
		)
		(pad "10" smd oval
			(at 0.2 -2.33 180)
			(size 0.3556 1.8034)
			(layers "F.Cu" "F.Mask" "F.Paste")
			(net "P3V3_40G_B2_VCC_RX")
		)
		(pad "11" smd oval
			(at 1.000001 -2.33 180)
			(size 0.3556 1.8034)
			(layers "F.Cu" "F.Mask" "F.Paste")
			(net "ETH40G_B2_SCL")
		)
		(pad "12" smd oval
			(at 1.799999 -2.33 180)
			(size 0.3556 1.8034)
			(layers "F.Cu" "F.Mask" "F.Paste")
			(net "ETH40G_B2_SDA")
		)
		(pad "13" smd oval
			(at 2.6 -2.33 180)
			(size 0.3556 1.8034)
			(layers "F.Cu" "F.Mask" "F.Paste")
			(net "GND")
		)
		(pad "14" smd oval
			(at 3.400001 -2.33 180)
			(size 0.3556 1.8034)
			(layers "F.Cu" "F.Mask" "F.Paste")
			(net "ETH40G_B2_RX2P")
		)
		(pad "15" smd oval
			(at 4.199999 -2.33 180)
			(size 0.3556 1.8034)
			(layers "F.Cu" "F.Mask" "F.Paste")
			(net "ETH40G_B2_RX2N")
		)
		(pad "16" smd oval
			(at 5 -2.33 180)
			(size 0.3556 1.8034)
			(layers "F.Cu" "F.Mask" "F.Paste")
			(net "GND")
		)
		(pad "17" smd oval
			(at 5.800001 -2.33 180)
			(size 0.3556 1.8034)
			(layers "F.Cu" "F.Mask" "F.Paste")
			(net "ETH40G_B2_RX0P")
		)
		(pad "18" smd oval
			(at 6.6 -2.33 180)
			(size 0.3556 1.8034)
			(layers "F.Cu" "F.Mask" "F.Paste")
			(net "ETH40G_B2_RX0N")
		)
		(pad "19" smd oval
			(at 7.4 -2.33 180)
			(size 0.3556 1.8034)
			(layers "F.Cu" "F.Mask" "F.Paste")
			(net "GND")
		)
		(pad "20" smd oval
			(at 7.000001 -4.830001 180)
			(size 0.3556 1.8034)
			(layers "F.Cu" "F.Mask" "F.Paste")
			(net "GND")
		)
		(pad "21" smd oval
			(at 6.2 -4.830001 180)
			(size 0.3556 1.8034)
			(layers "F.Cu" "F.Mask" "F.Paste")
			(net "ETH40G_B2_RX1N")
		)
		(pad "22" smd oval
			(at 5.399999 -4.830001 180)
			(size 0.3556 1.8034)
			(layers "F.Cu" "F.Mask" "F.Paste")
			(net "ETH40G_B2_RX1P")
		)
		(pad "23" smd oval
			(at 4.600001 -4.830001 180)
			(size 0.3556 1.8034)
			(layers "F.Cu" "F.Mask" "F.Paste")
			(net "GND")
		)
		(pad "24" smd oval
			(at 3.8 -4.830001 180)
			(size 0.3556 1.8034)
			(layers "F.Cu" "F.Mask" "F.Paste")
			(net "ETH40G_B2_RX3N")
		)
		(pad "25" smd oval
			(at 2.999999 -4.830001 180)
			(size 0.3556 1.8034)
			(layers "F.Cu" "F.Mask" "F.Paste")
			(net "ETH40G_B2_RX3P")
		)
		(pad "26" smd oval
			(at 2.200001 -4.830001 180)
			(size 0.3556 1.8034)
			(layers "F.Cu" "F.Mask" "F.Paste")
			(net "GND")
		)
		(pad "27" smd oval
			(at 1.4 -4.830001 180)
			(size 0.3556 1.8034)
			(layers "F.Cu" "F.Mask" "F.Paste")
			(net "ETH40G_B2_MODPRS_N")
		)
		(pad "28" smd oval
			(at 0.599999 -4.830001 180)
			(size 0.3556 1.8034)
			(layers "F.Cu" "F.Mask" "F.Paste")
			(net "ETH40G_B2_INT_N")
		)
		(pad "29" smd oval
			(at -0.2 -4.830001 180)
			(size 0.3556 1.8034)
			(layers "F.Cu" "F.Mask" "F.Paste")
			(net "P3V3_40G_B2_VCC_TX")
		)
		(pad "30" smd oval
			(at -1.000001 -4.830001 180)
			(size 0.3556 1.8034)
			(layers "F.Cu" "F.Mask" "F.Paste")
			(net "P3V3_40G_B2_VCC1")
		)
		(pad "31" smd oval
			(at -1.799999 -4.830001 180)
			(size 0.3556 1.8034)
			(layers "F.Cu" "F.Mask" "F.Paste")
			(net "ETH40G_B2_LPMODE")
		)
		(pad "32" smd oval
			(at -2.6 -4.830001 180)
			(size 0.3556 1.8034)
			(layers "F.Cu" "F.Mask" "F.Paste")
			(net "GND")
		)
		(pad "33" smd oval
			(at -3.400001 -4.830001 180)
			(size 0.3556 1.8034)
			(layers "F.Cu" "F.Mask" "F.Paste")
			(net "ETH40G_B2_TX2P")
		)
		(pad "34" smd oval
			(at -4.199999 -4.830001 180)
			(size 0.3556 1.8034)
			(layers "F.Cu" "F.Mask" "F.Paste")
			(net "ETH40G_B2_TX2N")
		)
		(pad "35" smd oval
			(at -5 -4.830001 180)
			(size 0.3556 1.8034)
			(layers "F.Cu" "F.Mask" "F.Paste")
			(net "GND")
		)
		(pad "36" smd oval
			(at -5.800001 -4.830001 180)
			(size 0.3556 1.8034)
			(layers "F.Cu" "F.Mask" "F.Paste")
			(net "ETH40G_B2_TX0P")
		)
		(pad "37" smd oval
			(at -6.6 -4.830001 180)
			(size 0.3556 1.8034)
			(layers "F.Cu" "F.Mask" "F.Paste")
			(net "ETH40G_B2_TX0N")
		)
		(pad "38" smd oval
			(at -7.4 -4.830001 180)
			(size 0.3556 1.8034)
			(layers "F.Cu" "F.Mask" "F.Paste")
			(net "GND")
		)
		(zone
			(layers "F.Cu" "B.Cu" "In1.Cu" "In2.Cu" "In3.Cu" "In4.Cu" "In5.Cu" "In6.Cu")
			(hatch none 0.5)
			(connect_pads
				(clearance 0)
			)
			(min_thickness 0.25)
			(keepout
				(tracks not_allowed)
				(vias allowed)
				(pads allowed)
				(copperpour not_allowed)
				(footprints allowed)
			)
			(placement
				(enabled no)
				(sheetname "")
			)
			(fill
				(thermal_gap 0.5)
				(thermal_bridge_width 0.5)
				(island_removal_mode 0)
			)
			(polygon
				(pts
					(arc
						(start -104.805701 36.160001)
						(mid -102.494301 36.160001)
						(end -104.805701 36.160001)
					)
				)
			)
		)
		(zone
			(layers "F.Cu" "B.Cu" "In1.Cu" "In2.Cu" "In3.Cu" "In4.Cu" "In5.Cu" "In6.Cu")
			(hatch none 0.5)
			(connect_pads
				(clearance 0)
			)
			(min_thickness 0.25)
			(keepout
				(tracks not_allowed)
				(vias allowed)
				(pads allowed)
				(copperpour not_allowed)
				(footprints allowed)
			)
			(placement
				(enabled no)
				(sheetname "")
			)
			(fill
				(thermal_gap 0.5)
				(thermal_bridge_width 0.5)
				(island_removal_mode 0)
			)
			(polygon
				(pts
					(arc
						(start -88.005699 36.160001)
						(mid -85.694299 36.160001)
						(end -88.005699 36.160001)
					)
				)
			)
		)
	)
	(footprint ""
		(layer "F.Cu")
		(at -110.8456 7.493 180)
		(property "Reference" "R63"
			(at -2.79146 -0.18542 0)
			(unlocked yes)
			(layer "F.SilkS")
			(effects
				(font
					(size 0.762 0.5334)
					(thickness 0.1016)
				)
			)
		)
		(property "Value" ""
			(at 0 0 180)
			(layer "F.Fab")
			(effects
				(font
					(size 1.27 1.27)
				)
			)
		)
		(duplicate_pad_numbers_are_jumpers no)
		(fp_line
			(start 0 -0.381)
			(end 0 0.381)
			(stroke
				(width 0.127)
				(type default)
			)
			(layer "F.SilkS")
		)
		(fp_poly
			(pts
				(xy 1.255601 0.656399) (xy -1.255601 0.656399) (xy -1.255601 -0.6564) (xy 1.255601 -0.6564)
			)
			(stroke
				(width 0)
				(type default)
			)
			(fill no)
			(layer "F.CrtYd")
		)
		(fp_line
			(start 0.800001 0.399999)
			(end 0.800001 -0.399999)
			(stroke
				(width 0.1)
				(type default)
			)
			(layer "F.Fab")
		)
		(fp_line
			(start 0.800001 -0.399999)
			(end -0.800001 -0.399999)
			(stroke
				(width 0.1)
				(type default)
			)
			(layer "F.Fab")
		)
		(fp_line
			(start -0.800001 0.399999)
			(end 0.800001 0.399999)
			(stroke
				(width 0.1)
				(type default)
			)
			(layer "F.Fab")
		)
		(fp_line
			(start -0.800001 -0.399999)
			(end -0.800001 0.399999)
			(stroke
				(width 0.1)
				(type default)
			)
			(layer "F.Fab")
		)
		(pad "1" smd rect
			(at -0.650001 0 180)
			(size 0.7112 0.8128)
			(layers "F.Cu" "F.Mask" "F.Paste")
			(net "ETH40G_B2_MODSEL_N")
		)
		(pad "2" smd rect
			(at 0.650001 0)
			(size 0.7112 0.8128)
			(layers "F.Cu" "F.Mask" "F.Paste")
			(net "GND")
		)
	)
	(footprint ""
		(layer "F.Cu")
		(at -296.145801 2.730602 180)
		(property "Reference" "R21"
			(at -3.029801 -0.101498 0)
			(unlocked yes)
			(layer "F.SilkS")
			(effects
				(font
					(size 0.762 0.5334)
					(thickness 0.1016)
				)
			)
		)
		(property "Value" ""
			(at 0 0 180)
			(layer "F.Fab")
			(effects
				(font
					(size 1.27 1.27)
				)
			)
		)
		(duplicate_pad_numbers_are_jumpers no)
		(fp_line
			(start 0 -0.381)
			(end 0 0.381)
			(stroke
				(width 0.127)
				(type default)
			)
			(layer "F.SilkS")
		)
		(fp_poly
			(pts
				(xy 1.255601 0.6564) (xy -1.255601 0.6564) (xy -1.255601 -0.656399) (xy 1.255601 -0.656399)
			)
			(stroke
				(width 0)
				(type default)
			)
			(fill no)
			(layer "F.CrtYd")
		)
		(fp_line
			(start 0.800001 0.4)
			(end 0.800001 -0.399999)
			(stroke
				(width 0.1)
				(type default)
			)
			(layer "F.Fab")
		)
		(fp_line
			(start 0.800001 -0.399999)
			(end -0.800001 -0.399999)
			(stroke
				(width 0.1)
				(type default)
			)
			(layer "F.Fab")
		)
		(fp_line
			(start -0.800001 0.4)
			(end 0.800001 0.4)
			(stroke
				(width 0.1)
				(type default)
			)
			(layer "F.Fab")
		)
		(fp_line
			(start -0.800001 -0.399999)
			(end -0.800001 0.4)
			(stroke
				(width 0.1)
				(type default)
			)
			(layer "F.Fab")
		)
		(pad "1" smd rect
			(at -0.650001 0 180)
			(size 0.7112 0.8128)
			(layers "F.Cu" "F.Mask" "F.Paste")
			(net "ETH10G_B1_TX_DIS")
		)
		(pad "2" smd rect
			(at 0.650001 0)
			(size 0.7112 0.8128)
			(layers "F.Cu" "F.Mask" "F.Paste")
			(net "GND")
		)
	)
	(footprint ""
		(layer "F.Cu")
		(at -63.563401 43.345202 180)
		(property "Reference" "C11"
			(at 2.603599 0.000102 0)
			(unlocked yes)
			(layer "F.SilkS")
			(effects
				(font
					(size 0.762 0.5334)
					(thickness 0.1016)
				)
			)
		)
		(property "Value" ""
			(at 0 0 180)
			(layer "F.Fab")
			(effects
				(font
					(size 1.27 1.27)
				)
			)
		)
		(duplicate_pad_numbers_are_jumpers no)
		(fp_poly
			(pts
				(xy -0.9993 0.504) (xy -0.9993 -0.503999) (xy 0.999299 -0.503999) (xy 0.999299 0.504)
			)
			(stroke
				(width 0)
				(type default)
			)
			(fill no)
			(layer "F.CrtYd")
		)
		(fp_line
			(start 0.499999 0.25)
			(end -0.499999 0.25)
			(stroke
				(width 0.1)
				(type default)
			)
			(layer "F.Fab")
		)
		(fp_line
			(start 0.499999 -0.249999)
			(end 0.499999 0.25)
			(stroke
				(width 0.1)
				(type default)
			)
			(layer "F.Fab")
		)
		(fp_line
			(start -0.499999 0.25)
			(end -0.499999 -0.249999)
			(stroke
				(width 0.1)
				(type default)
			)
			(layer "F.Fab")
		)
		(fp_line
			(start -0.499999 -0.249999)
			(end 0.499999 -0.249999)
			(stroke
				(width 0.1)
				(type default)
			)
			(layer "F.Fab")
		)
		(pad "1" smd rect
			(at -0.4572 0 270)
			(size 0.508 0.5842)
			(layers "F.Cu" "F.Mask" "F.Paste")
			(net "P3V3_10G_B2_VCCR")
		)
		(pad "2" smd rect
			(at 0.4572 0 270)
			(size 0.508 0.5842)
			(layers "F.Cu" "F.Mask" "F.Paste")
			(net "GND")
		)
	)
	(footprint ""
		(layer "F.Cu")
		(at -110.8456 16.0274)
		(property "Reference" "R67"
			(at 3.1496 0.0127 0)
			(unlocked yes)
			(layer "F.SilkS")
			(effects
				(font
					(size 0.762 0.5334)
					(thickness 0.1016)
				)
			)
		)
		(property "Value" ""
			(at 0 0 0)
			(layer "F.Fab")
			(effects
				(font
					(size 1.27 1.27)
				)
			)
		)
		(duplicate_pad_numbers_are_jumpers no)
		(fp_line
			(start 0 -0.381)
			(end 0 0.381)
			(stroke
				(width 0.127)
				(type default)
			)
			(layer "F.SilkS")
		)
		(fp_poly
			(pts
				(xy 1.255601 0.6564) (xy -1.255601 0.6564) (xy -1.255601 -0.656399) (xy 1.255601 -0.656399)
			)
			(stroke
				(width 0)
				(type default)
			)
			(fill no)
			(layer "F.CrtYd")
		)
		(fp_line
			(start -0.800001 -0.399999)
			(end -0.800001 0.399999)
			(stroke
				(width 0.1)
				(type default)
			)
			(layer "F.Fab")
		)
		(fp_line
			(start -0.800001 0.399999)
			(end 0.800001 0.399999)
			(stroke
				(width 0.1)
				(type default)
			)
			(layer "F.Fab")
		)
		(fp_line
			(start 0.800001 -0.399999)
			(end -0.800001 -0.399999)
			(stroke
				(width 0.1)
				(type default)
			)
			(layer "F.Fab")
		)
		(fp_line
			(start 0.800001 0.399999)
			(end 0.800001 -0.399999)
			(stroke
				(width 0.1)
				(type default)
			)
			(layer "F.Fab")
		)
		(pad "1" smd rect
			(at -0.650001 0)
			(size 0.7112 0.8128)
			(layers "F.Cu" "F.Mask" "F.Paste")
			(net "P3V3_B2_QSFP")
		)
		(pad "2" smd rect
			(at 0.650001 0 180)
			(size 0.7112 0.8128)
			(layers "F.Cu" "F.Mask" "F.Paste")
			(net "ETH40G_B2_SDA")
		)
	)
	(footprint ""
		(layer "F.Cu")
		(at -80.137 12.065)
		(property "Reference" "R66"
			(at -2.921 0.0381 0)
			(unlocked yes)
			(layer "F.SilkS")
			(effects
				(font
					(size 0.762 0.5334)
					(thickness 0.1016)
				)
			)
		)
		(property "Value" ""
			(at 0 0 0)
			(layer "F.Fab")
			(effects
				(font
					(size 1.27 1.27)
				)
			)
		)
		(duplicate_pad_numbers_are_jumpers no)
		(fp_line
			(start 0 -0.381)
			(end 0 0.381)
			(stroke
				(width 0.127)
				(type default)
			)
			(layer "F.SilkS")
		)
		(fp_poly
			(pts
				(xy 1.255601 0.6564) (xy -1.255601 0.6564) (xy -1.255601 -0.656399) (xy 1.255601 -0.656399)
			)
			(stroke
				(width 0)
				(type default)
			)
			(fill no)
			(layer "F.CrtYd")
		)
		(fp_line
			(start -0.800001 -0.399999)
			(end -0.800001 0.399999)
			(stroke
				(width 0.1)
				(type default)
			)
			(layer "F.Fab")
		)
		(fp_line
			(start -0.800001 0.399999)
			(end 0.800001 0.399999)
			(stroke
				(width 0.1)
				(type default)
			)
			(layer "F.Fab")
		)
		(fp_line
			(start 0.800001 -0.399999)
			(end -0.800001 -0.399999)
			(stroke
				(width 0.1)
				(type default)
			)
			(layer "F.Fab")
		)
		(fp_line
			(start 0.800001 0.399999)
			(end 0.800001 -0.399999)
			(stroke
				(width 0.1)
				(type default)
			)
			(layer "F.Fab")
		)
		(pad "1" smd rect
			(at -0.650001 0)
			(size 0.7112 0.8128)
			(layers "F.Cu" "F.Mask" "F.Paste")
			(net "ETH40G_B2_MODPRS_N")
		)
		(pad "2" smd rect
			(at 0.650001 0 180)
			(size 0.7112 0.8128)
			(layers "F.Cu" "F.Mask" "F.Paste")
			(net "ETH40G_B2_PRES_N")
		)
	)
)
